#ISCELL
  pure_quanta quanta_title_block_c *
  *
#CELL
  pure_quanta genoa_sp5 *
  page50_i143
#CELL
  pure_quanta genoa_sp5 *
  page50_i144
#ISCELL
  standard offpage *
  page50_i195
#ISCELL
  mstr_standard tap *
  page50_i198
#ISCELL
  mstr_standard tap *
  page50_i199
#ISCELL
  standard tap *
  page50_i202
#ISCELL
  standard tap *
  page50_i203
#ISCELL
  standard tap *
  page50_i204
#ISCELL
  standard tap *
  page50_i208
#ISCELL
  standard tap *
  page50_i209
#ISCELL
  standard tap *
  page50_i212
#ISCELL
  standard tap *
  page50_i213
#ISCELL
  standard tap *
  page50_i214
#ISCELL
  standard tap *
  page50_i218
#ISCELL
  standard tap *
  page50_i219
#ISCELL
  standard tap *
  page50_i222
#ISCELL
  standard tap *
  page50_i223
#ISCELL
  standard tap *
  page50_i224
#ISCELL
  standard tap *
  page50_i225
#ISCELL
  standard offpage *
  page50_i228
#ISCELL
  mstr_standard tap *
  page50_i241
#ISCELL
  standard tap *
  page50_i242
#ISCELL
  standard tap *
  page50_i243
#ISCELL
  mstr_standard tap *
  page50_i244
#ISCELL
  standard tap *
  page50_i245
#ISCELL
  standard tap *
  page50_i246
#ISCELL
  standard tap *
  page50_i247
#ISCELL
  standard tap *
  page50_i248
#ISCELL
  standard tap *
  page50_i249
#ISCELL
  standard tap *
  page50_i250
#ISCELL
  standard tap *
  page50_i251
#ISCELL
  standard tap *
  page50_i257
#ISCELL
  standard tap *
  page50_i258
#ISCELL
  standard tap *
  page50_i259
#ISCELL
  standard tap *
  page50_i260
#ISCELL
  standard tap *
  page50_i261
#ISCELL
  mstr_standard tap *
  page50_i262
#ISCELL
  mstr_standard tap *
  page50_i263
#ISCELL
  mstr_standard tap *
  page50_i266
#ISCELL
  standard tap *
  page50_i267
#ISCELL
  standard tap *
  page50_i268
#ISCELL
  standard tap *
  page50_i271
#ISCELL
  standard tap *
  page50_i272
#ISCELL
  standard tap *
  page50_i276
#ISCELL
  standard tap *
  page50_i277
#ISCELL
  standard tap *
  page50_i278
#ISCELL
  standard tap *
  page50_i281
#ISCELL
  standard tap *
  page50_i282
#ISCELL
  standard tap *
  page50_i286
#ISCELL
  standard tap *
  page50_i287
#ISCELL
  standard tap *
  page50_i288
#ISCELL
  standard tap *
  page50_i291
#ISCELL
  standard offpage *
  page50_i295
#ISCELL
  standard tap *
  page50_i296
#ISCELL
  standard tap *
  page50_i298
#ISCELL
  standard tap *
  page50_i299
#ISCELL
  standard tap *
  page50_i300
#ISCELL
  standard tap *
  page50_i303
#ISCELL
  standard tap *
  page50_i304
#ISCELL
  standard tap *
  page50_i308
#ISCELL
  standard tap *
  page50_i309
#ISCELL
  standard tap *
  page50_i310
#ISCELL
  standard tap *
  page50_i313
#ISCELL
  standard tap *
  page50_i314
#ISCELL
  standard offpage *
  page50_i318
#ISCELL
  standard tap *
  page50_i320
#ISCELL
  standard tap *
  page50_i321
#ISCELL
  standard tap *
  page50_i322
#ISCELL
  standard tap *
  page50_i325
#ISCELL
  standard tap *
  page50_i327
#ISCELL
  mstr_standard tap *
  page50_i398
#ISCELL
  mstr_standard tap *
  page50_i399
#ISCELL
  standard tap *
  page50_i400
#ISCELL
  standard tap *
  page50_i401
#ISCELL
  standard tap *
  page50_i402
#ISCELL
  standard tap *
  page50_i403
#ISCELL
  standard tap *
  page50_i404
#ISCELL
  standard tap *
  page50_i405
#ISCELL
  standard tap *
  page50_i406
#ISCELL
  standard tap *
  page50_i407
#ISCELL
  standard tap *
  page50_i408
#ISCELL
  standard tap *
  page50_i409
#ISCELL
  standard tap *
  page50_i410
#ISCELL
  standard tap *
  page50_i411
#ISCELL
  standard tap *
  page50_i412
#ISCELL
  standard tap *
  page50_i413
#ISCELL
  standard offpage *
  page50_i414
#ISCELL
  standard offpage *
  page50_i415
#ISCELL
  mstr_standard tap *
  page50_i416
#ISCELL
  mstr_standard tap *
  page50_i417
#ISCELL
  standard tap *
  page50_i418
#ISCELL
  standard tap *
  page50_i419
#ISCELL
  standard tap *
  page50_i420
#ISCELL
  standard tap *
  page50_i421
#ISCELL
  standard tap *
  page50_i422
#ISCELL
  standard tap *
  page50_i423
#ISCELL
  standard tap *
  page50_i424
#ISCELL
  standard tap *
  page50_i425
#ISCELL
  standard tap *
  page50_i426
#ISCELL
  standard tap *
  page50_i427
#ISCELL
  standard tap *
  page50_i428
#ISCELL
  standard tap *
  page50_i429
#ISCELL
  standard tap *
  page50_i430
#ISCELL
  standard tap *
  page50_i431
#ISCELL
  standard offpage *
  page50_i432
#ISCELL
  mstr_standard tap *
  page50_i433
#ISCELL
  mstr_standard tap *
  page50_i434
#ISCELL
  standard tap *
  page50_i435
#ISCELL
  standard tap *
  page50_i436
#ISCELL
  standard tap *
  page50_i437
#ISCELL
  standard tap *
  page50_i438
#ISCELL
  standard tap *
  page50_i439
#ISCELL
  standard tap *
  page50_i440
#ISCELL
  standard tap *
  page50_i441
#ISCELL
  standard tap *
  page50_i442
#ISCELL
  standard tap *
  page50_i443
#ISCELL
  standard tap *
  page50_i444
#ISCELL
  standard tap *
  page50_i445
#ISCELL
  standard tap *
  page50_i446
#ISCELL
  standard tap *
  page50_i447
#ISCELL
  standard tap *
  page50_i448
#ISCELL
  mstr_standard tap *
  page50_i449
#ISCELL
  mstr_standard tap *
  page50_i450
#ISCELL
  standard tap *
  page50_i451
#ISCELL
  standard tap *
  page50_i452
#ISCELL
  standard tap *
  page50_i453
#ISCELL
  standard tap *
  page50_i454
#ISCELL
  standard tap *
  page50_i455
#ISCELL
  standard tap *
  page50_i456
#ISCELL
  standard tap *
  page50_i457
#ISCELL
  standard tap *
  page50_i458
#ISCELL
  standard tap *
  page50_i459
#ISCELL
  standard tap *
  page50_i460
#ISCELL
  standard tap *
  page50_i461
#ISCELL
  standard tap *
  page50_i462
#ISCELL
  standard tap *
  page50_i463
#ISCELL
  standard tap *
  page50_i464
#ISCELL
  standard offpage *
  page50_i465
